# TIMECARD (Time Appliance Project (Time Card)) — schematic netlist excerpt (pin names and nets, part order shuffled) for the footprints in the layout excerpt that follows; sources: Cadence DE-HDL packaged netlist, KiCad conversion of R4006-B0001-02_R01.brd

R130  RESISTOR  10KOHM 1%  pkg SMC_0402R_H016  page 24 : \1\ = FT_USB_DETECT ; \2\ = SG
C23  CAPACITOR  0.1UF 10%  pkg SMC_0402R_H022  page 9 : \1\ = C_PCIEREFCLKN ; \2\ = PCIE_REFCLKN

(kicad_pcb
	(version 20260206)
	(generator "pcbnew")
	(generator_version "10.0")
	(general
		(thickness 1.6)
		(legacy_teardrops no)
	)
	(paper "A4")
	(title_block
		(title "timecard-production-celestica-r4006 — R4006-B0001-02_R01.brd")
		(comment 1 "Time Appliance Project (Time Card) / footprints 761-762 of 1113")
	)
	(layers
		(0 "F.Cu" signal "TOP")
		(4 "In1.Cu" signal "L02_GND1")
		(6 "In2.Cu" signal "L03_SIG1")
		(8 "In3.Cu" signal "L04_GND2")
		(10 "In4.Cu" signal "L05_VCC1")
		(12 "In5.Cu" signal "L06_VCC2")
		(14 "In6.Cu" signal "L07_GND3")
		(16 "In7.Cu" signal "L08_SIG2")
		(18 "In8.Cu" signal "L09_GND4")
		(2 "B.Cu" signal "BOTTOM")
		(9 "F.Adhes" user "F.Adhesive")
		(11 "B.Adhes" user "B.Adhesive")
		(13 "F.Paste" user "Package Geometry/Pastemask Top")
		(15 "B.Paste" user "Package Geometry/Pastemask Bottom")
		(5 "F.SilkS" user "Ref Des/Silkscreen Top")
		(7 "B.SilkS" user "Ref Des/Silkscreen Bottom")
		(1 "F.Mask" user "Board Geometry/Soldermask Top")
		(3 "B.Mask" user "Board Geometry/Soldermask Bottom")
		(17 "Dwgs.User" user "User.Drawings")
		(19 "Cmts.User" user "User.Comments")
		(21 "Eco1.User" user "User.Eco1")
		(23 "Eco2.User" user "User.Eco2")
		(25 "Edge.Cuts" user "Board Geometry/Outline")
		(27 "Margin" user)
		(31 "F.CrtYd" user "Package Geometry/Place Bound Top")
		(29 "B.CrtYd" user "Package Geometry/Place Bound Bottom")
		(35 "F.Fab" user "Ref Des/Assembly Top")
		(33 "B.Fab" user "Ref Des/Assembly Bottom")
	)
	(footprint ""
		(layer "B.Cu")
		(at 25.273 -91.059 90)
		(property "Reference" "R130"
			(at 2.286 -5.11937 270)
			(unlocked yes)
			(layer "B.SilkS")
			(effects
				(font
					(size 0.7874 0.5842)
					(thickness 0.1524)
				)
				(justify mirror)
			)
		)
		(property "Value" "VAL*"
			(at -0.02032 2.13233 90)
			(unlocked yes)
			(layer "B.Fab")
			(hide yes)
			(effects
				(font
					(size 0.7874 0.5842)
					(thickness 0.1524)
				)
				(justify mirror)
			)
		)
		(property "Tolerance" "TOL*"
			(at -0.044704 3.05435 90)
			(unlocked yes)
			(layer "Cmts.User")
			(hide yes)
			(effects
				(font
					(size 0.7874 0.5842)
					(thickness 0.1524)
				)
				(justify mirror)
			)
		)
		(property "User Part Number" "PARTNUM*"
			(at -0.02032 4.024884 90)
			(unlocked yes)
			(layer "Cmts.User")
			(hide yes)
			(effects
				(font
					(size 0.7874 0.5842)
					(thickness 0.1524)
				)
				(justify mirror)
			)
		)
		(property "Device Type" "RESISTOR-G155-11002-01,10KOHM,A"
			(at -0.008382 1.210564 90)
			(unlocked yes)
			(layer "B.Fab")
			(hide yes)
			(effects
				(font
					(size 0.7874 0.5842)
					(thickness 0.1524)
				)
				(justify mirror)
			)
		)
		(duplicate_pad_numbers_are_jumpers no)
		(fp_line
			(start 1.143 -0.5588)
			(end 1.143 0.5588)
			(stroke
				(width 0.1)
				(type default)
			)
			(layer "B.SilkS")
		)
		(fp_line
			(start -1.143 -0.5588)
			(end 1.143 -0.5588)
			(stroke
				(width 0.1)
				(type default)
			)
			(layer "B.SilkS")
		)
		(fp_line
			(start 1.143 0.5588)
			(end -1.143 0.5588)
			(stroke
				(width 0.1)
				(type default)
			)
			(layer "B.SilkS")
		)
		(fp_line
			(start -1.143 0.5588)
			(end -1.143 -0.5588)
			(stroke
				(width 0.1)
				(type default)
			)
			(layer "B.SilkS")
		)
		(fp_poly
			(pts
				(xy 1.143 0.5588) (xy -1.143 0.5588) (xy -1.143 -0.5588) (xy 1.143 -0.5588)
			)
			(stroke
				(width 0)
				(type default)
			)
			(fill no)
			(layer "B.CrtYd")
		)
		(fp_line
			(start 0.508 -0.3048)
			(end 0.508 0.3048)
			(stroke
				(width 0.1)
				(type default)
			)
			(layer "B.Fab")
		)
		(fp_line
			(start -0.508 -0.3048)
			(end 0.508 -0.3048)
			(stroke
				(width 0.1)
				(type default)
			)
			(layer "B.Fab")
		)
		(fp_line
			(start 0.508 0.3048)
			(end -0.508 0.3048)
			(stroke
				(width 0.1)
				(type default)
			)
			(layer "B.Fab")
		)
		(fp_line
			(start -0.508 0.3048)
			(end -0.508 -0.3048)
			(stroke
				(width 0.1)
				(type default)
			)
			(layer "B.Fab")
		)
		(pad "1" smd rect
			(at 0.5334 0 270)
			(size 0.7112 0.6096)
			(layers "B.Cu" "B.Mask" "B.Paste")
			(net "FT_USB_DETECT")
		)
		(pad "2" smd rect
			(at -0.5334 0 270)
			(size 0.7112 0.6096)
			(layers "B.Cu" "B.Mask" "B.Paste")
			(net "SG")
		)
		(zone
			(layer "B.Cu")
			(hatch none 0.5)
			(connect_pads
				(clearance 0)
			)
			(min_thickness 0.25)
			(keepout
				(tracks not_allowed)
				(vias allowed)
				(pads allowed)
				(copperpour not_allowed)
				(footprints allowed)
			)
			(placement
				(enabled no)
				(sheetname "")
			)
			(fill
				(thermal_gap 0.5)
				(thermal_bridge_width 0.5)
				(island_removal_mode 0)
			)
			(polygon
				(pts
					(xy 25.5778 -91.1352) (xy 24.9682 -91.1352) (xy 24.9682 -90.9828) (xy 25.5778 -90.9828)
				)
			)
		)
		(zone
			(layer "B.Cu")
			(hatch none 0.5)
			(connect_pads
				(clearance 0)
			)
			(min_thickness 0.25)
			(keepout
				(tracks allowed)
				(vias not_allowed)
				(pads allowed)
				(copperpour not_allowed)
				(footprints allowed)
			)
			(placement
				(enabled no)
				(sheetname "")
			)
			(fill
				(thermal_gap 0.5)
				(thermal_bridge_width 0.5)
				(island_removal_mode 0)
			)
			(polygon
				(pts
					(xy 25.5778 -91.1352) (xy 24.9682 -91.1352) (xy 24.9682 -90.9828) (xy 25.5778 -90.9828)
				)
			)
		)
	)
	(footprint ""
		(layer "B.Cu")
		(at 60.784994 -15.367 -90)
		(property "Reference" "C23"
			(at 2.3368 -0.059436 270)
			(unlocked yes)
			(layer "B.SilkS")
			(effects
				(font
					(size 0.7874 0.5842)
					(thickness 0.1524)
				)
				(justify mirror)
			)
		)
		(property "Value" "VAL*"
			(at -0.0762 2.067306 270)
			(unlocked yes)
			(layer "B.Fab")
			(hide yes)
			(effects
				(font
					(size 0.7874 0.5842)
					(thickness 0.1524)
				)
				(justify mirror)
			)
		)
		(property "Tolerance" "TOL*"
			(at -0.0762 3.032506 270)
			(unlocked yes)
			(layer "Cmts.User")
			(hide yes)
			(effects
				(font
					(size 0.7874 0.5842)
					(thickness 0.1524)
				)
				(justify mirror)
			)
		)
		(property "User Part Number" "PARTNUM*"
			(at -0.1016 4.023106 270)
			(unlocked yes)
			(layer "Cmts.User")
			(hide yes)
			(effects
				(font
					(size 0.7874 0.5842)
					(thickness 0.1524)
				)
				(justify mirror)
			)
		)
		(property "Device Type" "CAPACITOR-G105-0B104-CK,0.1UF,A"
			(at -0.0508 1.127506 270)
			(unlocked yes)
			(layer "B.Fab")
			(hide yes)
			(effects
				(font
					(size 0.7874 0.5842)
					(thickness 0.1524)
				)
				(justify mirror)
			)
		)
		(duplicate_pad_numbers_are_jumpers no)
		(fp_line
			(start -1.143 0.5588)
			(end -1.143 -0.5588)
			(stroke
				(width 0.1)
				(type default)
			)
			(layer "B.SilkS")
		)
		(fp_line
			(start 1.143 0.5588)
			(end -1.143 0.5588)
			(stroke
				(width 0.1)
				(type default)
			)
			(layer "B.SilkS")
		)
		(fp_line
			(start -1.143 -0.5588)
			(end 1.143 -0.5588)
			(stroke
				(width 0.1)
				(type default)
			)
			(layer "B.SilkS")
		)
		(fp_line
			(start 1.143 -0.5588)
			(end 1.143 0.5588)
			(stroke
				(width 0.1)
				(type default)
			)
			(layer "B.SilkS")
		)
		(fp_rect
			(start 1.143 0.5588)
			(end -1.143 -0.5588)
			(stroke
				(width 0)
				(type default)
			)
			(fill no)
			(layer "B.CrtYd")
		)
		(fp_line
			(start -0.508 0.3048)
			(end -0.508 -0.3048)
			(stroke
				(width 0.1)
				(type default)
			)
			(layer "B.Fab")
		)
		(fp_line
			(start 0.508 0.3048)
			(end -0.508 0.3048)
			(stroke
				(width 0.1)
				(type default)
			)
			(layer "B.Fab")
		)
		(fp_line
			(start -0.508 -0.3048)
			(end 0.508 -0.3048)
			(stroke
				(width 0.1)
				(type default)
			)
			(layer "B.Fab")
		)
		(fp_line
			(start 0.508 -0.3048)
			(end 0.508 0.3048)
			(stroke
				(width 0.1)
				(type default)
			)
			(layer "B.Fab")
		)
		(pad "1" smd rect
			(at 0.5334 0 90)
			(size 0.7112 0.6096)
			(layers "B.Cu" "B.Mask" "B.Paste")
			(net "C_PCIEREFCLKN")
		)
		(pad "2" smd rect
			(at -0.5334 0 90)
			(size 0.7112 0.6096)
			(layers "B.Cu" "B.Mask" "B.Paste")
			(net "PCIE_REFCLKN")
		)
		(zone
			(layer "B.Cu")
			(hatch none 0.5)
			(connect_pads
				(clearance 0)
			)
			(min_thickness 0.25)
			(keepout
				(tracks allowed)
				(vias not_allowed)
				(pads allowed)
				(copperpour not_allowed)
				(footprints allowed)
			)
			(placement
				(enabled no)
				(sheetname "")
			)
			(fill
				(thermal_gap 0.5)
				(thermal_bridge_width 0.5)
				(island_removal_mode 0)
			)
			(polygon
				(pts
					(xy 60.480194 -15.2908) (xy 61.089794 -15.2908) (xy 61.089794 -15.4432) (xy 60.480194 -15.4432)
				)
			)
		)
	)
)
